(kicad_pcb
	(version 20260206)
	(generator "pcbnew")
	(generator_version "10.0")
	(general
		(thickness 1.6)
		(legacy_teardrops no)
	)
	(paper "A4")
	(title_block
		(title "baseboard — 13948-1b.1110WZS1818.brd")
		(comment 1 "Honey Badger (Wiwynn) / footprints 35-41 of 2523")
	)
	(layers
		(0 "F.Cu" signal "TOP")
		(4 "In1.Cu" signal "L2GND")
		(6 "In2.Cu" signal "L3")
		(8 "In3.Cu" signal "L4VCC")
		(10 "In4.Cu" signal "L5VCC")
		(12 "In5.Cu" signal "L6")
		(14 "In6.Cu" signal "L7GND")
		(2 "B.Cu" signal "BOTTOM")
		(9 "F.Adhes" user "F.Adhesive")
		(11 "B.Adhes" user "B.Adhesive")
		(13 "F.Paste" user "Package Geometry/Pastemask Top")
		(15 "B.Paste" user "Package Geometry/Pastemask Bottom")
		(5 "F.SilkS" user "Ref Des/Silkscreen Top")
		(7 "B.SilkS" user "Ref Des/Silkscreen Bottom")
		(1 "F.Mask" user "Board Geometry/Soldermask Top")
		(3 "B.Mask" user "Board Geometry/Soldermask Bottom")
		(17 "Dwgs.User" user "User.Drawings")
		(19 "Cmts.User" user "User.Comments")
		(21 "Eco1.User" user "User.Eco1")
		(23 "Eco2.User" user "User.Eco2")
		(25 "Edge.Cuts" user "Board Geometry/Outline")
		(27 "Margin" user)
		(31 "F.CrtYd" user "Package Geometry/Place Bound Top")
		(29 "B.CrtYd" user "Package Geometry/Place Bound Bottom")
		(35 "F.Fab" user "Ref Des/Assembly Top")
		(33 "B.Fab" user "Ref Des/Assembly Bottom")
	)
	(footprint ""
		(layer "F.Cu")
		(at 187.833 -140.589 -90)
		(property "Reference" "SR764"
			(at 0 0 270)
			(layer "F.SilkS")
			(hide yes)
			(effects
				(font
					(size 1.27 1.27)
				)
			)
		)
		(property "Value" "0R2J-2-GP"
			(at 0.064008 -3.993896 270)
			(unlocked yes)
			(layer "F.Fab")
			(hide yes)
			(effects
				(font
					(size 1.016 1.016)
					(thickness 0.1524)
				)
			)
		)
		(property "Device Type" "R402H16"
			(at 0.064008 -5.517896 270)
			(unlocked yes)
			(layer "F.Fab")
			(hide yes)
			(effects
				(font
					(size 1.016 1.016)
					(thickness 0.1524)
				)
			)
		)
		(duplicate_pad_numbers_are_jumpers no)
		(fp_line
			(start -0.508 -0.9398)
			(end -0.508 0.9398)
			(stroke
				(width 0.1524)
				(type default)
			)
			(layer "F.SilkS")
		)
		(fp_line
			(start 0.508 -0.9398)
			(end -0.508 -0.9398)
			(stroke
				(width 0.1524)
				(type default)
			)
			(layer "F.SilkS")
		)
		(fp_rect
			(start -0.508 0.9398)
			(end 0.508 -0.9398)
			(stroke
				(width 0)
				(type default)
			)
			(fill no)
			(layer "F.CrtYd")
		)
		(fp_rect
			(start -0.508 0.9398)
			(end 0.508 -0.9398)
			(stroke
				(width 0)
				(type default)
			)
			(fill no)
			(layer "F.Fab")
		)
		(pad "1" smd custom
			(at 0 -0.4445 270)
			(size 0.1397 0.1397)
			(layers "F.Cu" "F.Mask" "F.Paste")
			(net "EXP_EEPROM_WP")
			(options
				(clearance outline)
				(anchor circle)
			)
			(primitives
				(gr_poly
					(pts
						(arc
							(start -0.1778 -0.2794)
							(mid -0.249642 -0.249642)
							(end -0.2794 -0.1778)
						)
						(arc
							(start -0.2794 0.1778)
							(mid -0.249642 0.249642)
							(end -0.1778 0.2794)
						)
						(arc
							(start 0.1778 0.2794)
							(mid 0.249642 0.249642)
							(end 0.2794 0.1778)
						)
						(arc
							(start 0.2794 -0.1778)
							(mid 0.249642 -0.249642)
							(end 0.1778 -0.2794)
						)
					)
					(width 0)
					(fill yes)
				)
			)
		)
		(pad "2" smd custom
			(at 0 0.4445 270)
			(size 0.1397 0.1397)
			(layers "F.Cu" "F.Mask" "F.Paste")
			(net "GND")
			(options
				(clearance outline)
				(anchor circle)
			)
			(primitives
				(gr_poly
					(pts
						(arc
							(start -0.1778 -0.2794)
							(mid -0.249642 -0.249642)
							(end -0.2794 -0.1778)
						)
						(arc
							(start -0.2794 0.1778)
							(mid -0.249642 0.249642)
							(end -0.1778 0.2794)
						)
						(arc
							(start 0.1778 0.2794)
							(mid 0.249642 0.249642)
							(end 0.2794 0.1778)
						)
						(arc
							(start 0.2794 -0.1778)
							(mid 0.249642 -0.249642)
							(end 0.1778 -0.2794)
						)
					)
					(width 0)
					(fill yes)
				)
			)
		)
	)
	(footprint ""
		(layer "F.Cu")
		(at 94.215966 -61.468)
		(property "Reference" "STP32"
			(at 0 0 0)
			(layer "F.SilkS")
			(hide yes)
			(effects
				(font
					(size 1.27 1.27)
				)
			)
		)
		(property "Value" "TPAD28"
			(at 0.0127 -1.8034 0)
			(unlocked yes)
			(layer "F.Fab")
			(hide yes)
			(effects
				(font
					(size 1.016 1.016)
					(thickness 0.1524)
				)
			)
		)
		(property "Device Type" "TPAD28"
			(at 0.0127 -3.3274 0)
			(unlocked yes)
			(layer "F.Fab")
			(hide yes)
			(effects
				(font
					(size 1.016 1.016)
					(thickness 0.1524)
				)
			)
		)
		(duplicate_pad_numbers_are_jumpers no)
		(fp_poly
			(pts
				(arc
					(start 0.3556 0)
					(mid -0.3556 0)
					(end 0.3556 0)
				)
			)
			(stroke
				(width 0)
				(type default)
			)
			(fill no)
			(layer "F.CrtYd")
		)
		(fp_poly
			(pts
				(arc
					(start 0.6096 0)
					(mid -0.6096 0)
					(end 0.6096 0)
				)
			)
			(stroke
				(width 0)
				(type default)
			)
			(fill no)
			(layer "F.Fab")
		)
		(pad "1" smd circle
			(at 0 0)
			(size 0.7112 0.7112)
			(layers "F.Cu" "F.Mask" "F.Paste")
			(net "ICE0_TDI")
		)
	)
	(footprint ""
		(layer "F.Cu")
		(at 50.8 -103.251 -90)
		(property "Reference" "SCN5"
			(at 0 0 270)
			(layer "F.SilkS")
			(hide yes)
			(effects
				(font
					(size 1.27 1.27)
				)
			)
		)
		(property "Value" "JWT-CON4-S24-GP"
			(at -7.3787 1.4351 270)
			(unlocked yes)
			(layer "F.Fab")
			(hide yes)
			(effects
				(font
					(size 1.016 1.016)
					(thickness 0.1524)
				)
			)
		)
		(property "Device Type" "A2541WV0-1QX4PA-6T"
			(at -7.3787 -0.0889 270)
			(unlocked yes)
			(layer "F.Fab")
			(hide yes)
			(effects
				(font
					(size 1.016 1.016)
					(thickness 0.1524)
				)
			)
		)
		(duplicate_pad_numbers_are_jumpers no)
		(fp_line
			(start -5.334 1.524)
			(end 5.334 1.524)
			(stroke
				(width 0.1524)
				(type default)
			)
			(layer "F.SilkS")
		)
		(fp_line
			(start 5.334 1.524)
			(end 5.334 -1.524)
			(stroke
				(width 0.1524)
				(type default)
			)
			(layer "F.SilkS")
		)
		(fp_line
			(start -5.334 -1.524)
			(end -5.334 1.524)
			(stroke
				(width 0.1524)
				(type default)
			)
			(layer "F.SilkS")
		)
		(fp_line
			(start 5.334 -1.524)
			(end -5.334 -1.524)
			(stroke
				(width 0.1524)
				(type default)
			)
			(layer "F.SilkS")
		)
		(fp_line
			(start -5.461 -1.651)
			(end -5.461 -0.381)
			(stroke
				(width 0.4064)
				(type default)
			)
			(layer "F.SilkS")
		)
		(fp_line
			(start -4.191 -1.651)
			(end -5.461 -1.651)
			(stroke
				(width 0.4064)
				(type default)
			)
			(layer "F.SilkS")
		)
		(fp_circle
			(center -3.81 0)
			(end -3.81 -1.0668)
			(stroke
				(width 0.3048)
				(type default)
			)
			(fill no)
			(layer "F.SilkS")
		)
		(fp_circle
			(center -1.27 0)
			(end -1.27 -1.0668)
			(stroke
				(width 0.3048)
				(type default)
			)
			(fill no)
			(layer "F.SilkS")
		)
		(fp_circle
			(center 1.27 0)
			(end 1.27 -1.0668)
			(stroke
				(width 0.3048)
				(type default)
			)
			(fill no)
			(layer "F.SilkS")
		)
		(fp_circle
			(center 3.81 0)
			(end 3.81 -1.0668)
			(stroke
				(width 0.3048)
				(type default)
			)
			(fill no)
			(layer "F.SilkS")
		)
		(fp_rect
			(start -5.08 1.27)
			(end 5.08 -1.27)
			(stroke
				(width 0)
				(type default)
			)
			(fill no)
			(layer "F.CrtYd")
		)
		(fp_poly
			(pts
				(xy -5.588 1.778) (xy -5.588 -1.778) (xy 5.588 -1.778) (xy 5.588 1.2573) (xy 5.08 1.2573) (xy 5.08 -1.27)
				(xy -5.08 -1.27) (xy -5.08 1.27) (xy 5.588 1.27) (xy 5.588 1.778)
			)
			(stroke
				(width 0)
				(type default)
			)
			(fill no)
			(layer "F.CrtYd")
		)
		(fp_rect
			(start -5.588 1.778)
			(end 5.588 -1.778)
			(stroke
				(width 0)
				(type default)
			)
			(fill no)
			(layer "F.Fab")
		)
		(pad "1" thru_hole circle
			(at -3.81 0 270)
			(size 1.4224 1.4224)
			(drill 1.016)
			(layers "*.Cu" "*.Mask")
			(remove_unused_layers no)
			(net "P5V_STBY")
			(clearance 0.1524)
			(thermal_gap 0.1524)
		)
		(pad "2" thru_hole circle
			(at -1.27 0 270)
			(size 1.4224 1.4224)
			(drill 1.016)
			(layers "*.Cu" "*.Mask")
			(remove_unused_layers no)
			(net "SAS_SDBTX_R")
			(clearance 0.1524)
			(thermal_gap 0.1524)
		)
		(pad "3" thru_hole circle
			(at 1.27 0 270)
			(size 1.4224 1.4224)
			(drill 1.016)
			(layers "*.Cu" "*.Mask")
			(remove_unused_layers no)
			(net "SAS_SDBRX_R")
			(clearance 0.1524)
			(thermal_gap 0.1524)
		)
		(pad "4" thru_hole circle
			(at 3.81 0 270)
			(size 1.4224 1.4224)
			(drill 1.016)
			(layers "*.Cu" "*.Mask")
			(remove_unused_layers no)
			(net "GND")
			(clearance 0.1524)
			(thermal_gap 0.1524)
		)
	)
	(footprint ""
		(layer "F.Cu")
		(at 200.025 -197.231 180)
		(property "Reference" "C264"
			(at 0 0 180)
			(layer "F.SilkS")
			(hide yes)
			(effects
				(font
					(size 1.27 1.27)
				)
			)
		)
		(property "Value" "SCD1U16V2KX-3GP"
			(at 1.1811 -2.7051 180)
			(unlocked yes)
			(layer "F.Fab")
			(hide yes)
			(effects
				(font
					(size 1.016 1.016)
					(thickness 0.1524)
				)
			)
		)
		(property "Device Type" "C402H22"
			(at 1.1811 -4.2291 180)
			(unlocked yes)
			(layer "F.Fab")
			(hide yes)
			(effects
				(font
					(size 1.016 1.016)
					(thickness 0.1524)
				)
			)
		)
		(duplicate_pad_numbers_are_jumpers no)
		(fp_rect
			(start -0.4318 0.9525)
			(end 0.4318 -0.9525)
			(stroke
				(width 0)
				(type default)
			)
			(fill no)
			(layer "F.CrtYd")
		)
		(fp_rect
			(start -0.4318 0.9525)
			(end 0.4318 -0.9525)
			(stroke
				(width 0)
				(type default)
			)
			(fill no)
			(layer "F.Fab")
		)
		(pad "1" smd custom
			(at 0 -0.4445 180)
			(size 0.1524 0.1524)
			(layers "F.Cu" "F.Mask" "F.Paste")
			(net "P3V3_STBY")
			(options
				(clearance outline)
				(anchor circle)
			)
			(primitives
				(gr_poly
					(pts
						(arc
							(start 0.3048 -0.2032)
							(mid 0.275042 -0.275042)
							(end 0.2032 -0.3048)
						)
						(arc
							(start -0.2032 -0.3048)
							(mid -0.275042 -0.275042)
							(end -0.3048 -0.2032)
						)
						(arc
							(start -0.3048 0.2032)
							(mid -0.275042 0.275042)
							(end -0.2032 0.3048)
						)
						(arc
							(start 0.2032 0.3048)
							(mid 0.275042 0.275042)
							(end 0.3048 0.2032)
						)
					)
					(width 0)
					(fill yes)
				)
			)
		)
		(pad "2" smd custom
			(at 0 0.4445 180)
			(size 0.1524 0.1524)
			(layers "F.Cu" "F.Mask" "F.Paste")
			(net "GND")
			(options
				(clearance outline)
				(anchor circle)
			)
			(primitives
				(gr_poly
					(pts
						(arc
							(start 0.3048 -0.2032)
							(mid 0.275042 -0.275042)
							(end 0.2032 -0.3048)
						)
						(arc
							(start -0.2032 -0.3048)
							(mid -0.275042 -0.275042)
							(end -0.3048 -0.2032)
						)
						(arc
							(start -0.3048 0.2032)
							(mid -0.275042 0.275042)
							(end -0.2032 0.3048)
						)
						(arc
							(start 0.2032 0.3048)
							(mid 0.275042 0.275042)
							(end 0.3048 0.2032)
						)
					)
					(width 0)
					(fill yes)
				)
			)
		)
	)
	(footprint ""
		(layer "F.Cu")
		(at 300.482 -60.198 -90)
		(property "Reference" "R209"
			(at 0 0 270)
			(layer "F.SilkS")
			(hide yes)
			(effects
				(font
					(size 1.27 1.27)
				)
			)
		)
		(property "Value" "0R2J-2-GP"
			(at 0.064008 -3.993896 270)
			(unlocked yes)
			(layer "F.Fab")
			(hide yes)
			(effects
				(font
					(size 1.016 1.016)
					(thickness 0.1524)
				)
			)
		)
		(property "Device Type" "R402H16"
			(at 0.064008 -5.517896 270)
			(unlocked yes)
			(layer "F.Fab")
			(hide yes)
			(effects
				(font
					(size 1.016 1.016)
					(thickness 0.1524)
				)
			)
		)
		(duplicate_pad_numbers_are_jumpers no)
		(fp_line
			(start -0.508 -0.9398)
			(end -0.508 0.9398)
			(stroke
				(width 0.1524)
				(type default)
			)
			(layer "F.SilkS")
		)
		(fp_line
			(start 0.508 -0.9398)
			(end -0.508 -0.9398)
			(stroke
				(width 0.1524)
				(type default)
			)
			(layer "F.SilkS")
		)
		(fp_rect
			(start -0.508 0.9398)
			(end 0.508 -0.9398)
			(stroke
				(width 0)
				(type default)
			)
			(fill no)
			(layer "F.CrtYd")
		)
		(fp_rect
			(start -0.508 0.9398)
			(end 0.508 -0.9398)
			(stroke
				(width 0)
				(type default)
			)
			(fill no)
			(layer "F.Fab")
		)
		(pad "1" smd custom
			(at 0 -0.4445 270)
			(size 0.1397 0.1397)
			(layers "F.Cu" "F.Mask" "F.Paste")
			(net "SMB_LAN_ALERT_N")
			(options
				(clearance outline)
				(anchor circle)
			)
			(primitives
				(gr_poly
					(pts
						(arc
							(start -0.1778 -0.2794)
							(mid -0.249642 -0.249642)
							(end -0.2794 -0.1778)
						)
						(arc
							(start -0.2794 0.1778)
							(mid -0.249642 0.249642)
							(end -0.1778 0.2794)
						)
						(arc
							(start 0.1778 0.2794)
							(mid 0.249642 0.249642)
							(end 0.2794 0.1778)
						)
						(arc
							(start 0.2794 -0.1778)
							(mid 0.249642 -0.249642)
							(end 0.1778 -0.2794)
						)
					)
					(width 0)
					(fill yes)
				)
			)
		)
		(pad "2" smd custom
			(at 0 0.4445 270)
			(size 0.1397 0.1397)
			(layers "F.Cu" "F.Mask" "F.Paste")
			(net "I2C_BMC_10G_ALERT#")
			(options
				(clearance outline)
				(anchor circle)
			)
			(primitives
				(gr_poly
					(pts
						(arc
							(start -0.1778 -0.2794)
							(mid -0.249642 -0.249642)
							(end -0.2794 -0.1778)
						)
						(arc
							(start -0.2794 0.1778)
							(mid -0.249642 0.249642)
							(end -0.1778 0.2794)
						)
						(arc
							(start 0.1778 0.2794)
							(mid 0.249642 0.249642)
							(end 0.2794 0.1778)
						)
						(arc
							(start 0.2794 -0.1778)
							(mid 0.249642 -0.249642)
							(end 0.1778 -0.2794)
						)
					)
					(width 0)
					(fill yes)
				)
			)
		)
	)
	(footprint ""
		(layer "F.Cu")
		(at 316.865 -167.894 -90)
		(property "Reference" "R460"
			(at 0 0 270)
			(layer "F.SilkS")
			(hide yes)
			(effects
				(font
					(size 1.27 1.27)
				)
			)
		)
		(property "Value" "0R2J-2-GP"
			(at 0.064008 -3.993896 270)
			(unlocked yes)
			(layer "F.Fab")
			(hide yes)
			(effects
				(font
					(size 1.016 1.016)
					(thickness 0.1524)
				)
			)
		)
		(property "Device Type" "R402H16"
			(at 0.064008 -5.517896 270)
			(unlocked yes)
			(layer "F.Fab")
			(hide yes)
			(effects
				(font
					(size 1.016 1.016)
					(thickness 0.1524)
				)
			)
		)
		(duplicate_pad_numbers_are_jumpers no)
		(fp_line
			(start -0.508 -0.9398)
			(end -0.508 0.9398)
			(stroke
				(width 0.1524)
				(type default)
			)
			(layer "F.SilkS")
		)
		(fp_line
			(start 0.508 -0.9398)
			(end -0.508 -0.9398)
			(stroke
				(width 0.1524)
				(type default)
			)
			(layer "F.SilkS")
		)
		(fp_rect
			(start -0.508 0.9398)
			(end 0.508 -0.9398)
			(stroke
				(width 0)
				(type default)
			)
			(fill no)
			(layer "F.CrtYd")
		)
		(fp_rect
			(start -0.508 0.9398)
			(end 0.508 -0.9398)
			(stroke
				(width 0)
				(type default)
			)
			(fill no)
			(layer "F.Fab")
		)
		(pad "1" smd custom
			(at 0 -0.4445 270)
			(size 0.1397 0.1397)
			(layers "F.Cu" "F.Mask" "F.Paste")
			(net "BMC_I2C_B_SDA")
			(options
				(clearance outline)
				(anchor circle)
			)
			(primitives
				(gr_poly
					(pts
						(arc
							(start -0.1778 -0.2794)
							(mid -0.249642 -0.249642)
							(end -0.2794 -0.1778)
						)
						(arc
							(start -0.2794 0.1778)
							(mid -0.249642 0.249642)
							(end -0.1778 0.2794)
						)
						(arc
							(start 0.1778 0.2794)
							(mid 0.249642 0.249642)
							(end 0.2794 0.1778)
						)
						(arc
							(start 0.2794 -0.1778)
							(mid 0.249642 -0.249642)
							(end 0.1778 -0.2794)
						)
					)
					(width 0)
					(fill yes)
				)
			)
		)
		(pad "2" smd custom
			(at 0 0.4445 270)
			(size 0.1397 0.1397)
			(layers "F.Cu" "F.Mask" "F.Paste")
			(net "BMC0_SMB7_DAT")
			(options
				(clearance outline)
				(anchor circle)
			)
			(primitives
				(gr_poly
					(pts
						(arc
							(start -0.1778 -0.2794)
							(mid -0.249642 -0.249642)
							(end -0.2794 -0.1778)
						)
						(arc
							(start -0.2794 0.1778)
							(mid -0.249642 0.249642)
							(end -0.1778 0.2794)
						)
						(arc
							(start 0.1778 0.2794)
							(mid 0.249642 0.249642)
							(end 0.2794 0.1778)
						)
						(arc
							(start 0.2794 -0.1778)
							(mid 0.249642 -0.249642)
							(end 0.1778 -0.2794)
						)
					)
					(width 0)
					(fill yes)
				)
			)
		)
	)
	(footprint ""
		(layer "F.Cu")
		(at 63.881 -227.076)
		(property "Reference" "Q23"
			(at 0 0 0)
			(layer "F.SilkS")
			(hide yes)
			(effects
				(font
					(size 1.27 1.27)
				)
			)
		)
		(property "Value" "PSMN0R9-25YLC-GP"
			(at -4.2799 -0.4572 0)
			(unlocked yes)
			(layer "F.Fab")
			(hide yes)
			(effects
				(font
					(size 1.016 1.016)
					(thickness 0.1524)
				)
			)
		)
		(property "Device Type" "LFPAK-5PH48-U"
			(at -4.2799 -1.9812 0)
			(unlocked yes)
			(layer "F.Fab")
			(hide yes)
			(effects
				(font
					(size 1.016 1.016)
					(thickness 0.1524)
				)
			)
		)
		(duplicate_pad_numbers_are_jumpers no)
		(fp_line
			(start -2.7559 -6.5532)
			(end -2.7559 1.0668)
			(stroke
				(width 0.1524)
				(type default)
			)
			(layer "F.SilkS")
		)
		(fp_line
			(start -2.7559 1.0668)
			(end 2.7559 1.0668)
			(stroke
				(width 0.1524)
				(type default)
			)
			(layer "F.SilkS")
		)
		(fp_line
			(start -1.7272 1.1684)
			(end -2.1082 1.1684)
			(stroke
				(width 0.3302)
				(type default)
			)
			(layer "F.SilkS")
		)
		(fp_line
			(start 2.7559 -6.5532)
			(end -2.7559 -6.5532)
			(stroke
				(width 0.1524)
				(type default)
			)
			(layer "F.SilkS")
		)
		(fp_line
			(start 2.7559 1.0668)
			(end 2.7559 -6.5532)
			(stroke
				(width 0.1524)
				(type default)
			)
			(layer "F.SilkS")
		)
		(fp_poly
			(pts
				(xy -2.3368 1.5748) (xy -1.905 1.143) (xy -1.4732 1.5748)
			)
			(stroke
				(width 0)
				(type default)
			)
			(fill yes)
			(layer "F.SilkS")
		)
		(fp_poly
			(pts
				(xy -2.5019 -4.02971) (xy -0.3302 -4.02971) (xy -0.3302 -6.30301) (xy -2.5019 -6.30301)
			)
			(stroke
				(width 0)
				(type default)
			)
			(fill yes)
			(layer "F.Paste")
		)
		(fp_poly
			(pts
				(xy -2.5019 -1.09601) (xy -0.3302 -1.09601) (xy -0.3302 -3.36931) (xy -2.5019 -3.36931)
			)
			(stroke
				(width 0)
				(type default)
			)
			(fill yes)
			(layer "F.Paste")
		)
		(fp_poly
			(pts
				(xy 0.3302 -4.02971) (xy 2.5019 -4.02971) (xy 2.5019 -6.30301) (xy 0.3302 -6.30301)
			)
			(stroke
				(width 0)
				(type default)
			)
			(fill yes)
			(layer "F.Paste")
		)
		(fp_poly
			(pts
				(xy 0.3302 -1.09601) (xy 2.5019 -1.09601) (xy 2.5019 -3.36931) (xy 0.3302 -3.36931)
			)
			(stroke
				(width 0)
				(type default)
			)
			(fill yes)
			(layer "F.Paste")
		)
		(fp_rect
			(start -2.4511 0.3048)
			(end 2.4511 -5.6896)
			(stroke
				(width 0)
				(type default)
			)
			(fill no)
			(layer "F.CrtYd")
		)
		(fp_poly
			(pts
				(xy -3.0099 1.3208) (xy -3.0099 -6.8072) (xy 3.0099 -6.8072) (xy 3.0099 -1.016) (xy 2.4511 -1.016)
				(xy 2.4511 -5.6896) (xy -2.4511 -5.6896) (xy -2.4511 0.3048) (xy 2.4511 0.3048) (xy 2.4511 -1.0033)
				(xy 3.0099 -1.0033) (xy 3.0099 1.3208)
			)
			(stroke
				(width 0)
				(type default)
			)
			(fill no)
			(layer "F.CrtYd")
		)
		(fp_rect
			(start -3.0099 1.3208)
			(end 3.0099 -6.8072)
			(stroke
				(width 0)
				(type default)
			)
			(fill no)
			(layer "F.Fab")
		)
		(pad "1" smd rect
			(at -1.905 0)
			(size 0.762 1.6256)
			(layers "F.Cu" "F.Mask" "F.Paste")
			(net "P12V")
		)
		(pad "2" smd rect
			(at -0.635 0)
			(size 0.762 1.6256)
			(layers "F.Cu" "F.Mask" "F.Paste")
			(net "P12V")
		)
		(pad "3" smd rect
			(at 0.635 0)
			(size 0.762 1.6256)
			(layers "F.Cu" "F.Mask" "F.Paste")
			(net "P12V")
		)
		(pad "4" smd rect
			(at 1.905 0)
			(size 0.762 1.6256)
			(layers "F.Cu" "F.Mask" "F.Paste")
			(net "MB0_12V_CTRL_GATE1")
		)
		(pad "5" smd rect
			(at 0 -3.69951)
			(size 5.0038 5.207)
			(layers "F.Cu" "F.Mask" "F.Paste")
			(net "MB0_P12V_MAIN_R")
		)
	)
)
